(kicad_pcb
	(version 20260206)
	(generator "pcbnew")
	(generator_version "10.0")
	(general
		(thickness 1.6)
		(legacy_teardrops no)
	)
	(paper "A4")
	(title_block
		(title "Bryce Canyon_SCC_16316-1_OCP.brd")
		(comment 1 "Bryce Canyon / footprints 177-184 of 1561")
	)
	(layers
		(0 "F.Cu" signal "TOP")
		(4 "In1.Cu" signal "L2GND")
		(6 "In2.Cu" signal "L3")
		(8 "In3.Cu" signal "L4VCC")
		(10 "In4.Cu" signal "L5VCC")
		(12 "In5.Cu" signal "L6")
		(14 "In6.Cu" signal "L7GND")
		(2 "B.Cu" signal "BOTTOM")
		(9 "F.Adhes" user "F.Adhesive")
		(11 "B.Adhes" user "B.Adhesive")
		(13 "F.Paste" user "Package Geometry/Pastemask Top")
		(15 "B.Paste" user "Package Geometry/Pastemask Bottom")
		(5 "F.SilkS" user "Ref Des/Silkscreen Top")
		(7 "B.SilkS" user "Ref Des/Silkscreen Bottom")
		(1 "F.Mask" user "Board Geometry/Soldermask Top")
		(3 "B.Mask" user "Board Geometry/Soldermask Bottom")
		(17 "Dwgs.User" user "User.Drawings")
		(19 "Cmts.User" user "User.Comments")
		(21 "Eco1.User" user "User.Eco1")
		(23 "Eco2.User" user "User.Eco2")
		(25 "Edge.Cuts" user "Board Geometry/Outline")
		(27 "Margin" user)
		(31 "F.CrtYd" user "Package Geometry/Place Bound Top")
		(29 "B.CrtYd" user "Package Geometry/Place Bound Bottom")
		(35 "F.Fab" user "Ref Des/Assembly Top")
		(33 "B.Fab" user "Ref Des/Assembly Bottom")
	)
	(footprint ""
		(layer "F.Cu")
		(at 139.37615 -63.045086)
		(property "Reference" "VIA15"
			(at 0 0 0)
			(layer "F.SilkS")
			(hide yes)
			(effects
				(font
					(size 1.27 1.27)
				)
			)
		)
		(property "Value" "100OHM-8L-1D6MM-L13-GP"
			(at 3.2893 0.0508 0)
			(unlocked yes)
			(layer "F.Fab")
			(hide yes)
			(effects
				(font
					(size 1.016 1.016)
					(thickness 0.1524)
				)
			)
		)
		(property "Device Type" "VIA-PCIE-4P-409091"
			(at 3.2893 -1.4732 0)
			(unlocked yes)
			(layer "F.Fab")
			(hide yes)
			(effects
				(font
					(size 1.016 1.016)
					(thickness 0.1524)
				)
			)
		)
		(duplicate_pad_numbers_are_jumpers no)
		(fp_rect
			(start -2.0447 0.4572)
			(end 2.0447 -0.4572)
			(stroke
				(width 0)
				(type default)
			)
			(fill no)
			(layer "F.CrtYd")
		)
		(fp_rect
			(start -2.0447 0.4572)
			(end 2.0447 -0.4572)
			(stroke
				(width 0)
				(type default)
			)
			(fill no)
			(layer "F.Fab")
		)
		(pad "1" thru_hole circle
			(at -1.5875 0)
			(size 0.508 0.508)
			(drill 0.254)
			(layers "*.Cu" "*.Mask")
			(remove_unused_layers no)
			(net "GND")
			(clearance 0.2032)
			(thermal_gap 0.2032)
		)
		(pad "2" thru_hole circle
			(at -0.5715 0)
			(size 0.508 0.508)
			(drill 0.254)
			(layers "*.Cu" "*.Mask")
			(remove_unused_layers no)
			(net "PHY_IOC_TO_SCC_C_46_DP")
			(clearance 0.2032)
			(thermal_gap 0.2032)
		)
		(pad "3" thru_hole circle
			(at 0.5715 0)
			(size 0.508 0.508)
			(drill 0.254)
			(layers "*.Cu" "*.Mask")
			(remove_unused_layers no)
			(net "PHY_IOC_TO_SCC_C_46_DN")
			(clearance 0.2032)
			(thermal_gap 0.2032)
		)
		(pad "4" thru_hole circle
			(at 1.5875 0)
			(size 0.508 0.508)
			(drill 0.254)
			(layers "*.Cu" "*.Mask")
			(remove_unused_layers no)
			(net "GND")
			(clearance 0.2032)
			(thermal_gap 0.2032)
		)
	)
	(footprint ""
		(layer "F.Cu")
		(at 160.274 -73.34123 90)
		(property "Reference" "C533"
			(at 0 0 90)
			(layer "F.SilkS")
			(hide yes)
			(effects
				(font
					(size 1.27 1.27)
				)
			)
		)
		(property "Value" "SCD1U16V2KX-3GP"
			(at 1.1811 -2.7051 90)
			(unlocked yes)
			(layer "F.Fab")
			(hide yes)
			(effects
				(font
					(size 1.016 1.016)
					(thickness 0.1524)
				)
			)
		)
		(property "Device Type" "C402H22"
			(at 1.1811 -4.2291 90)
			(unlocked yes)
			(layer "F.Fab")
			(hide yes)
			(effects
				(font
					(size 1.016 1.016)
					(thickness 0.1524)
				)
			)
		)
		(duplicate_pad_numbers_are_jumpers no)
		(fp_rect
			(start -0.4318 0.9525)
			(end 0.4318 -0.9525)
			(stroke
				(width 0)
				(type default)
			)
			(fill no)
			(layer "F.CrtYd")
		)
		(fp_rect
			(start -0.4318 0.9525)
			(end 0.4318 -0.9525)
			(stroke
				(width 0)
				(type default)
			)
			(fill no)
			(layer "F.Fab")
		)
		(pad "1" smd custom
			(at 0 -0.4445 90)
			(size 0.1524 0.1524)
			(layers "F.Cu" "F.Mask" "F.Paste")
			(net "P0V975_SENSE")
			(options
				(clearance outline)
				(anchor circle)
			)
			(primitives
				(gr_poly
					(pts
						(arc
							(start 0.3048 -0.2032)
							(mid 0.275042 -0.275042)
							(end 0.2032 -0.3048)
						)
						(arc
							(start -0.2032 -0.3048)
							(mid -0.275042 -0.275042)
							(end -0.3048 -0.2032)
						)
						(arc
							(start -0.3048 0.2032)
							(mid -0.275042 0.275042)
							(end -0.2032 0.3048)
						)
						(arc
							(start 0.2032 0.3048)
							(mid 0.275042 0.275042)
							(end 0.3048 0.2032)
						)
					)
					(width 0)
					(fill yes)
				)
			)
		)
		(pad "2" smd custom
			(at 0 0.4445 90)
			(size 0.1524 0.1524)
			(layers "F.Cu" "F.Mask" "F.Paste")
			(net "GND")
			(options
				(clearance outline)
				(anchor circle)
			)
			(primitives
				(gr_poly
					(pts
						(arc
							(start 0.3048 -0.2032)
							(mid 0.275042 -0.275042)
							(end 0.2032 -0.3048)
						)
						(arc
							(start -0.2032 -0.3048)
							(mid -0.275042 -0.275042)
							(end -0.3048 -0.2032)
						)
						(arc
							(start -0.3048 0.2032)
							(mid -0.275042 0.275042)
							(end -0.2032 0.3048)
						)
						(arc
							(start 0.2032 0.3048)
							(mid 0.275042 0.275042)
							(end 0.3048 0.2032)
						)
					)
					(width 0)
					(fill yes)
				)
			)
		)
	)
	(footprint ""
		(layer "F.Cu")
		(at 169.574718 -90.415618)
		(property "Reference" "R694"
			(at 0 0 0)
			(layer "F.SilkS")
			(hide yes)
			(effects
				(font
					(size 1.27 1.27)
				)
			)
		)
		(property "Value" "2D2R5F-2-GP"
			(at 0 -8.9535 0)
			(unlocked yes)
			(layer "F.Fab")
			(hide yes)
			(effects
				(font
					(size 1.27 1.016)
					(thickness 0.1524)
				)
			)
		)
		(property "Device Type" "R805H24"
			(at 0 -10.6299 0)
			(unlocked yes)
			(layer "F.Fab")
			(hide yes)
			(effects
				(font
					(size 1.27 1.016)
					(thickness 0.1524)
				)
			)
		)
		(duplicate_pad_numbers_are_jumpers no)
		(fp_line
			(start -0.889 -1.7018)
			(end -0.889 0.2794)
			(stroke
				(width 0.1524)
				(type default)
			)
			(layer "F.SilkS")
		)
		(fp_line
			(start -0.889 0.0762)
			(end -0.889 1.7018)
			(stroke
				(width 0.1524)
				(type default)
			)
			(layer "F.SilkS")
		)
		(fp_line
			(start -0.889 1.7018)
			(end 0.889 1.7018)
			(stroke
				(width 0.1524)
				(type default)
			)
			(layer "F.SilkS")
		)
		(fp_line
			(start 0.889 -1.7018)
			(end -0.889 -1.7018)
			(stroke
				(width 0.1524)
				(type default)
			)
			(layer "F.SilkS")
		)
		(fp_line
			(start 0.889 -1.7018)
			(end 0.889 -0.381)
			(stroke
				(width 0.1524)
				(type default)
			)
			(layer "F.SilkS")
		)
		(fp_line
			(start 0.889 1.7018)
			(end 0.889 -0.508)
			(stroke
				(width 0.1524)
				(type default)
			)
			(layer "F.SilkS")
		)
		(fp_poly
			(pts
				(xy 0.9652 -1.778) (xy 0.9652 1.778) (xy -0.9652 1.778) (xy -0.9652 -1.778)
			)
			(stroke
				(width 0)
				(type default)
			)
			(fill no)
			(layer "F.CrtYd")
		)
		(fp_rect
			(start -0.9652 1.778)
			(end 0.9652 -1.778)
			(stroke
				(width 0)
				(type default)
			)
			(fill no)
			(layer "F.Fab")
		)
		(pad "1" smd rect
			(at 0 -0.9652)
			(size 1.397 1.143)
			(layers "F.Cu" "F.Mask" "F.Paste")
			(net "VT235_VX")
		)
		(pad "2" smd rect
			(at 0 0.9652)
			(size 1.397 1.143)
			(layers "F.Cu" "F.Mask" "F.Paste")
			(net "VT235_VX_R")
		)
	)
	(footprint ""
		(layer "F.Cu")
		(at 33.9344 -46.5836)
		(property "Reference" "L30"
			(at 0 0 0)
			(layer "F.SilkS")
			(hide yes)
			(effects
				(font
					(size 1.27 1.27)
				)
			)
		)
		(property "Value" "BLM41PG600-GP"
			(at -3.690874 -7.441184 0)
			(unlocked yes)
			(layer "F.Fab")
			(hide yes)
			(effects
				(font
					(size 1.016 1.016)
					(thickness 0.1524)
				)
			)
		)
		(property "Device Type" "L451616H71"
			(at -3.690874 -5.917184 0)
			(unlocked yes)
			(layer "F.Fab")
			(hide yes)
			(effects
				(font
					(size 1.016 1.016)
					(thickness 0.1524)
				)
			)
		)
		(duplicate_pad_numbers_are_jumpers no)
		(fp_line
			(start -2.8702 -1.2954)
			(end -2.8702 1.2954)
			(stroke
				(width 0.1524)
				(type default)
			)
			(layer "F.SilkS")
		)
		(fp_line
			(start -2.8702 -1.2954)
			(end -2.8702 1.2954)
			(stroke
				(width 0.1524)
				(type default)
			)
			(layer "F.SilkS")
		)
		(fp_line
			(start -2.8702 1.2954)
			(end 2.8702 1.2954)
			(stroke
				(width 0.1524)
				(type default)
			)
			(layer "F.SilkS")
		)
		(fp_line
			(start -2.8702 1.2954)
			(end 2.8702 1.2954)
			(stroke
				(width 0.1524)
				(type default)
			)
			(layer "F.SilkS")
		)
		(fp_line
			(start 2.8702 -1.2954)
			(end -2.8702 -1.2954)
			(stroke
				(width 0.1524)
				(type default)
			)
			(layer "F.SilkS")
		)
		(fp_line
			(start 2.8702 -1.2954)
			(end -2.8702 -1.2954)
			(stroke
				(width 0.1524)
				(type default)
			)
			(layer "F.SilkS")
		)
		(fp_line
			(start 2.8702 1.2954)
			(end 2.8702 -1.2954)
			(stroke
				(width 0.1524)
				(type default)
			)
			(layer "F.SilkS")
		)
		(fp_line
			(start 2.8702 1.2954)
			(end 2.8702 -1.2954)
			(stroke
				(width 0.1524)
				(type default)
			)
			(layer "F.SilkS")
		)
		(fp_poly
			(pts
				(xy -2.8702 1.2954) (xy 2.8702 1.2954) (xy 2.8702 -1.2954) (xy -2.8702 -1.2954)
			)
			(stroke
				(width 0)
				(type default)
			)
			(fill no)
			(layer "F.CrtYd")
		)
		(fp_poly
			(pts
				(xy -2.8702 1.2954) (xy 2.8702 1.2954) (xy 2.8702 -1.2954) (xy -2.8702 -1.2954)
			)
			(stroke
				(width 0)
				(type default)
			)
			(fill no)
			(layer "F.Fab")
		)
		(pad "1" smd rect
			(at -1.9685 0)
			(size 1.3716 1.8796)
			(layers "F.Cu" "F.Mask" "F.Paste")
			(net "P12V_STBY_SCC")
		)
		(pad "2" smd rect
			(at 1.9685 0)
			(size 1.3716 1.8796)
			(layers "F.Cu" "F.Mask" "F.Paste")
			(net "P12V_STBY_VIN_Q7")
		)
	)
	(footprint ""
		(layer "F.Cu")
		(at 121.92 -92.0496 90)
		(property "Reference" "R564"
			(at 0 0 90)
			(layer "F.SilkS")
			(hide yes)
			(effects
				(font
					(size 1.27 1.27)
				)
			)
		)
		(property "Value" "10KR2F-2-GP"
			(at 0.064008 -3.993896 90)
			(unlocked yes)
			(layer "F.Fab")
			(hide yes)
			(effects
				(font
					(size 1.016 1.016)
					(thickness 0.1524)
				)
			)
		)
		(property "Device Type" "R402H16"
			(at 0.064008 -5.517896 90)
			(unlocked yes)
			(layer "F.Fab")
			(hide yes)
			(effects
				(font
					(size 1.016 1.016)
					(thickness 0.1524)
				)
			)
		)
		(duplicate_pad_numbers_are_jumpers no)
		(fp_line
			(start 0.508 -0.9398)
			(end -0.508 -0.9398)
			(stroke
				(width 0.1524)
				(type default)
			)
			(layer "F.SilkS")
		)
		(fp_line
			(start -0.508 -0.9398)
			(end -0.508 0.9398)
			(stroke
				(width 0.1524)
				(type default)
			)
			(layer "F.SilkS")
		)
		(fp_rect
			(start -0.508 0.9398)
			(end 0.508 -0.9398)
			(stroke
				(width 0)
				(type default)
			)
			(fill no)
			(layer "F.CrtYd")
		)
		(fp_rect
			(start -0.508 0.9398)
			(end 0.508 -0.9398)
			(stroke
				(width 0)
				(type default)
			)
			(fill no)
			(layer "F.Fab")
		)
		(pad "1" smd custom
			(at 0 -0.4445 90)
			(size 0.1397 0.1397)
			(layers "F.Cu" "F.Mask" "F.Paste")
			(net "BMC_SPARE_1_LS")
			(options
				(clearance outline)
				(anchor circle)
			)
			(primitives
				(gr_poly
					(pts
						(arc
							(start -0.1778 -0.2794)
							(mid -0.249642 -0.249642)
							(end -0.2794 -0.1778)
						)
						(arc
							(start -0.2794 0.1778)
							(mid -0.249642 0.249642)
							(end -0.1778 0.2794)
						)
						(arc
							(start 0.1778 0.2794)
							(mid 0.249642 0.249642)
							(end 0.2794 0.1778)
						)
						(arc
							(start 0.2794 -0.1778)
							(mid 0.249642 -0.249642)
							(end 0.1778 -0.2794)
						)
					)
					(width 0)
					(fill yes)
				)
			)
		)
		(pad "2" smd custom
			(at 0 0.4445 90)
			(size 0.1397 0.1397)
			(layers "F.Cu" "F.Mask" "F.Paste")
			(net "P1V8_E")
			(options
				(clearance outline)
				(anchor circle)
			)
			(primitives
				(gr_poly
					(pts
						(arc
							(start -0.1778 -0.2794)
							(mid -0.249642 -0.249642)
							(end -0.2794 -0.1778)
						)
						(arc
							(start -0.2794 0.1778)
							(mid -0.249642 0.249642)
							(end -0.1778 0.2794)
						)
						(arc
							(start 0.1778 0.2794)
							(mid 0.249642 0.249642)
							(end 0.2794 0.1778)
						)
						(arc
							(start 0.2794 -0.1778)
							(mid 0.249642 -0.249642)
							(end 0.1778 -0.2794)
						)
					)
					(width 0)
					(fill yes)
				)
			)
		)
	)
	(footprint ""
		(layer "F.Cu")
		(at 181.821836 -120.8024 90)
		(property "Reference" "C687"
			(at 0 0 90)
			(layer "F.SilkS")
			(hide yes)
			(effects
				(font
					(size 1.27 1.27)
				)
			)
		)
		(property "Value" "SC10U6D3V5KX-4GP"
			(at -0.0762 -6.1214 90)
			(unlocked yes)
			(layer "F.Fab")
			(hide yes)
			(effects
				(font
					(size 1.016 1.016)
					(thickness 0.1524)
				)
			)
		)
		(property "Device Type" "C805H58"
			(at -0.0762 -8.1534 90)
			(unlocked yes)
			(layer "F.Fab")
			(hide yes)
			(effects
				(font
					(size 1.016 1.016)
					(thickness 0.1524)
				)
			)
		)
		(duplicate_pad_numbers_are_jumpers no)
		(fp_line
			(start 0.635 0)
			(end -0.635 0)
			(stroke
				(width 0.508)
				(type default)
			)
			(layer "F.SilkS")
		)
		(fp_rect
			(start -0.9652 1.778)
			(end 0.9652 -1.778)
			(stroke
				(width 0)
				(type default)
			)
			(fill no)
			(layer "F.CrtYd")
		)
		(fp_poly
			(pts
				(xy -0.9652 -1.778) (xy 0.9652 -1.778) (xy 0.9652 1.778) (xy -0.9652 1.778)
			)
			(stroke
				(width 0)
				(type default)
			)
			(fill no)
			(layer "F.Fab")
		)
		(pad "1" smd rect
			(at 0 -0.9652 90)
			(size 1.397 1.143)
			(layers "F.Cu" "F.Mask" "F.Paste")
			(net "P1V8_E_OUT")
		)
		(pad "2" smd rect
			(at 0 0.9652 90)
			(size 1.397 1.143)
			(layers "F.Cu" "F.Mask" "F.Paste")
			(net "GND")
		)
	)
	(footprint ""
		(layer "F.Cu")
		(at 44.0182 -26.543 90)
		(property "Reference" "C673"
			(at 0 0 90)
			(layer "F.SilkS")
			(hide yes)
			(effects
				(font
					(size 1.27 1.27)
				)
			)
		)
		(property "Value" "SCD1U50V3KX-GP"
			(at 0 -2.8194 90)
			(unlocked yes)
			(layer "F.Fab")
			(hide yes)
			(effects
				(font
					(size 1.016 1.016)
					(thickness 0.1524)
				)
			)
		)
		(property "Device Type" "C603H36"
			(at 0 -4.3434 90)
			(unlocked yes)
			(layer "F.Fab")
			(hide yes)
			(effects
				(font
					(size 1.016 1.016)
					(thickness 0.1524)
				)
			)
		)
		(duplicate_pad_numbers_are_jumpers no)
		(fp_line
			(start 0.508 0)
			(end -0.508 0)
			(stroke
				(width 0.2032)
				(type default)
			)
			(layer "F.SilkS")
		)
		(fp_rect
			(start -0.5842 1.3335)
			(end 0.5842 -1.3335)
			(stroke
				(width 0)
				(type default)
			)
			(fill no)
			(layer "F.CrtYd")
		)
		(fp_rect
			(start -0.5842 1.3335)
			(end 0.5842 -1.3335)
			(stroke
				(width 0)
				(type default)
			)
			(fill no)
			(layer "F.Fab")
		)
		(pad "1" smd custom
			(at 0 -0.762 90)
			(size 0.2159 0.2159)
			(layers "F.Cu" "F.Mask" "F.Paste")
			(net "P0V9_VREF")
			(options
				(clearance outline)
				(anchor circle)
			)
			(primitives
				(gr_poly
					(pts
						(arc
							(start -0.3302 -0.4318)
							(mid -0.402042 -0.402042)
							(end -0.4318 -0.3302)
						)
						(arc
							(start -0.4318 0.3302)
							(mid -0.402042 0.402042)
							(end -0.3302 0.4318)
						)
						(arc
							(start 0.3302 0.4318)
							(mid 0.402042 0.402042)
							(end 0.4318 0.3302)
						)
						(arc
							(start 0.4318 -0.3302)
							(mid 0.402042 -0.402042)
							(end 0.3302 -0.4318)
						)
					)
					(width 0)
					(fill yes)
				)
			)
		)
		(pad "2" smd custom
			(at 0 0.762 90)
			(size 0.2159 0.2159)
			(layers "F.Cu" "F.Mask" "F.Paste")
			(net "P0V9_GSNS")
			(options
				(clearance outline)
				(anchor circle)
			)
			(primitives
				(gr_poly
					(pts
						(arc
							(start -0.3302 -0.4318)
							(mid -0.402042 -0.402042)
							(end -0.4318 -0.3302)
						)
						(arc
							(start -0.4318 0.3302)
							(mid -0.402042 0.402042)
							(end -0.3302 0.4318)
						)
						(arc
							(start 0.3302 0.4318)
							(mid 0.402042 0.402042)
							(end 0.4318 0.3302)
						)
						(arc
							(start 0.4318 -0.3302)
							(mid 0.402042 -0.402042)
							(end 0.3302 -0.4318)
						)
					)
					(width 0)
					(fill yes)
				)
			)
		)
	)
	(footprint ""
		(layer "F.Cu")
		(at 155.755594 -71.60387)
		(property "Reference" "R325"
			(at 0 0 0)
			(layer "F.SilkS")
			(hide yes)
			(effects
				(font
					(size 1.27 1.27)
				)
			)
		)
		(property "Value" "0R2J-2-GP"
			(at 0.064008 -3.993896 0)
			(unlocked yes)
			(layer "F.Fab")
			(hide yes)
			(effects
				(font
					(size 1.016 1.016)
					(thickness 0.1524)
				)
			)
		)
		(property "Device Type" "R402H16"
			(at 0.064008 -5.517896 0)
			(unlocked yes)
			(layer "F.Fab")
			(hide yes)
			(effects
				(font
					(size 1.016 1.016)
					(thickness 0.1524)
				)
			)
		)
		(duplicate_pad_numbers_are_jumpers no)
		(fp_line
			(start -0.508 -0.9398)
			(end -0.508 0.9398)
			(stroke
				(width 0.1524)
				(type default)
			)
			(layer "F.SilkS")
		)
		(fp_line
			(start 0.508 -0.9398)
			(end -0.508 -0.9398)
			(stroke
				(width 0.1524)
				(type default)
			)
			(layer "F.SilkS")
		)
		(fp_rect
			(start -0.508 0.9398)
			(end 0.508 -0.9398)
			(stroke
				(width 0)
				(type default)
			)
			(fill no)
			(layer "F.CrtYd")
		)
		(fp_rect
			(start -0.508 0.9398)
			(end 0.508 -0.9398)
			(stroke
				(width 0)
				(type default)
			)
			(fill no)
			(layer "F.Fab")
		)
		(pad "1" smd custom
			(at 0 -0.4445)
			(size 0.1397 0.1397)
			(layers "F.Cu" "F.Mask" "F.Paste")
			(net "VOL_SEN2_SCL")
			(options
				(clearance outline)
				(anchor circle)
			)
			(primitives
				(gr_poly
					(pts
						(arc
							(start -0.1778 -0.2794)
							(mid -0.249642 -0.249642)
							(end -0.2794 -0.1778)
						)
						(arc
							(start -0.2794 0.1778)
							(mid -0.249642 0.249642)
							(end -0.1778 0.2794)
						)
						(arc
							(start 0.1778 0.2794)
							(mid 0.249642 0.249642)
							(end 0.2794 0.1778)
						)
						(arc
							(start 0.2794 -0.1778)
							(mid 0.249642 -0.249642)
							(end 0.1778 -0.2794)
						)
					)
					(width 0)
					(fill yes)
				)
			)
		)
		(pad "2" smd custom
			(at 0 0.4445)
			(size 0.1397 0.1397)
			(layers "F.Cu" "F.Mask" "F.Paste")
			(net "I2C_SCC_SCL2")
			(options
				(clearance outline)
				(anchor circle)
			)
			(primitives
				(gr_poly
					(pts
						(arc
							(start -0.1778 -0.2794)
							(mid -0.249642 -0.249642)
							(end -0.2794 -0.1778)
						)
						(arc
							(start -0.2794 0.1778)
							(mid -0.249642 0.249642)
							(end -0.1778 0.2794)
						)
						(arc
							(start 0.1778 0.2794)
							(mid 0.249642 0.249642)
							(end 0.2794 0.1778)
						)
						(arc
							(start 0.2794 -0.1778)
							(mid 0.249642 -0.249642)
							(end 0.1778 -0.2794)
						)
					)
					(width 0)
					(fill yes)
				)
			)
		)
	)
)
